# BASEBOARD_FAB2 (Tioga Pass) — schematic netlist excerpt (pin names and nets, part order shuffled) for the footprints in the layout excerpt that follows; sources: Cadence DE-HDL packaged netlist, KiCad conversion of Wiwynn_Tioga_Pass_MB.brd

J4A2  SCONN288_H44441004  SCONN  pkg PIP  page 51
  \12v\(1)  = P12V_NVDIMM_DEF
  VSS(93)  = GND
  DQ(4)  = M_E_DQ<5>
  VSS(92)  = GND
  DQ(0)  = M_E_DQ<1>
  VSS(91)  = GND
  DQS9P  = M_E_DQS_DP<9>
  DQS9N  = M_E_DQS_DN<9>
  VSS(90)  = GND
  DQ(6)  = M_E_DQ<7>
  VSS(89)  = GND
  DQ(2)  = M_E_DQ<3>
  VSS(88)  = GND
  DQ(12)  = M_E_DQ<13>
  VSS(87)  = GND
  DQ(8)  = M_E_DQ<9>
  VSS(86)  = GND
  DQS10P  = M_E_DQS_DP<10>
  DQS10N  = M_E_DQS_DN<10>
  VSS(85)  = GND
  DQ(14)  = M_E_DQ<15>
  VSS(84)  = GND
  DQ(10)  = M_E_DQ<11>
  VSS(83)  = GND
  DQ(20)  = M_E_DQ<21>
  VSS(82)  = GND
  DQ(16)  = M_E_DQ<17>
  VSS(81)  = GND
  DQS11P  = M_E_DQS_DP<11>
  DQS11N  = M_E_DQS_DN<11>
  VSS(80)  = GND
  DQ(22)  = M_E_DQ<23>
  VSS(79)  = GND
  DQ(18)  = M_E_DQ<19>
  VSS(78)  = GND
  DQ(28)  = M_E_DQ<29>
  VSS(77)  = GND
  DQ(24)  = M_E_DQ<25>
  VSS(76)  = GND
  DQS12P  = M_E_DQS_DP<12>
  DQS12N  = M_E_DQS_DN<12>
  VSS(75)  = GND
  DQ(30)  = M_E_DQ<31>
  VSS(74)  = GND
  DQ(26)  = M_E_DQ<27>
  VSS(73)  = GND
  CB(4)  = M_E_ECC<5>
  VSS(72)  = GND
  CB(0)  = M_E_ECC<1>
  VSS(71)  = GND
  DQS17P  = M_E_DQS_DP<17>
  DQS17N  = M_E_DQS_DN<17>
  VSS(70)  = GND
  CB(6)  = M_E_ECC<7>
  VSS(69)  = GND
  CB(2)  = M_E_ECC<3>
  VSS(68)  = GND
  RESET_N  = M_DEF_RST_N
  VDD(25)  = PVDDQ_DEF
  CKE(0)  = M_E_CKE<0>
  VDD(24)  = PVDDQ_DEF
  ACT_N  = M_E_ACT_N
  BG(0)  = M_E_BG<0>
  VDD(23)  = PVDDQ_DEF
  A12  = M_E_MA<12>
  A9  = M_E_MA<9>
  VDD(22)  = PVDDQ_DEF
  A8  = M_E_MA<8>
  A6  = M_E_MA<6>
  VDD(21)  = PVDDQ_DEF
  A3  = M_E_MA<3>
  A1  = M_E_MA<1>
  VDD(20)  = PVDDQ_DEF
  CK0P  = M_E_CLK_DP<0>
  CK0N  = M_E_CLK_DN<0>
  VDD(19)  = PVDDQ_DEF
  VTT(1)  = PVTT_DEF
  EVENT_N  = FM_DIMM_EVENT_COD_N
  A0  = M_E_MA<0>
  VDD(18)  = PVDDQ_DEF
  BA(0)  = M_E_BA<0>
  A16_RAS_N  = M_E_MA<16>
  VDD(17)  = PVDDQ_DEF
  S0_N  = M_E_CS_N<0>
  VDD(16)  = PVDDQ_DEF
  A15_CAS_N  = M_E_MA<15>
  ODT(0)  = M_E_ODT<0>
  VDD(15)  = PVDDQ_DEF
  S1_N  = M_E_CS_N<1>
  VDD(14)  = PVDDQ_DEF
  ODT(1)  = M_E_ODT<1>
  VDD(13)  = PVDDQ_DEF
  S2_N_C(0)  = M_E_CS_N<2>
  VSS(67)  = GND
  DQ(36)  = M_E_DQ<37>
  VSS(66)  = GND
  DQ(32)  = M_E_DQ<33>
  VSS(65)  = GND
  DQS13P  = M_E_DQS_DP<13>
  DQS13N  = M_E_DQS_DN<13>
  VSS(64)  = GND
  DQ(38)  = M_E_DQ<39>
  VSS(63)  = GND
  DQ(34)  = M_E_DQ<35>
  VSS(62)  = GND
  DQ(44)  = M_E_DQ<45>
  VSS(61)  = GND
  DQ(40)  = M_E_DQ<41>
  VSS(60)  = GND
  DQS14P  = M_E_DQS_DP<14>
  DQS14N  = M_E_DQS_DN<14>
  VSS(59)  = GND
  DQ(46)  = M_E_DQ<47>
  VSS(58)  = GND
  DQ(42)  = M_E_DQ<43>
  VSS(57)  = GND
  DQ(52)  = M_E_DQ<53>
  VSS(56)  = GND
  DQ(48)  = M_E_DQ<49>
  VSS(55)  = GND
  DQS15P  = M_E_DQS_DP<15>
  DQS15N  = M_E_DQS_DN<15>
  VSS(54)  = GND
  DQ(54)  = M_E_DQ<55>
  VSS(53)  = GND
  DQ(50)  = M_E_DQ<51>
  VSS(52)  = GND
  DQ(60)  = M_E_DQ<61>
  VSS(51)  = GND
  DQ(56)  = M_E_DQ<57>
  VSS(50)  = GND
  DQS16P  = M_E_DQS_DP<16>
  DQS16N  = M_E_DQS_DN<16>
  VSS(49)  = GND
  DQ(62)  = M_E_DQ<63>
  VSS(48)  = GND
  DQ(58)  = M_E_DQ<59>
  VSS(47)  = GND
  SA(0)  = GND
  SA(1)  = PVPP_DEF
  SCL  = SMB_DDR_DEF_VPP_SCL
  VPP(4)  = PVPP_DEF
  VPP(3)  = PVPP_DEF
  RFU(2)  = TP_CH_E_DIMM_E0_RFU_2
  \12v\(0)  = P12V_NVDIMM_DEF
  VREFCA  = M_E_VREF
  VSS(46)  = GND
  DQ(5)  = M_E_DQ<4>
  VSS(45)  = GND
  DQ(1)  = M_E_DQ<0>
  VSS(44)  = GND
  DQS0N  = M_E_DQS_DN<0>
  DQS0P  = M_E_DQS_DP<0>
  VSS(43)  = GND
  DQ(7)  = M_E_DQ<6>
  VSS(42)  = GND
  DQ(3)  = M_E_DQ<2>
  VSS(41)  = GND
  DQ(13)  = M_E_DQ<12>
  VSS(40)  = GND
  DQ(9)  = M_E_DQ<8>
  VSS(39)  = GND
  DQS1N  = M_E_DQS_DN<1>
  DQS1P  = M_E_DQS_DP<1>
  VSS(38)  = GND
  DQ(15)  = M_E_DQ<14>
  VSS(37)  = GND
  DQ(11)  = M_E_DQ<10>
  VSS(36)  = GND
  DQ(21)  = M_E_DQ<20>
  VSS(35)  = GND
  DQ(17)  = M_E_DQ<16>
  VSS(34)  = GND
  DQS2N  = M_E_DQS_DN<2>
  DQS2P  = M_E_DQS_DP<2>
  VSS(33)  = GND
  DQ(23)  = M_E_DQ<22>
  VSS(32)  = GND
  DQ(19)  = M_E_DQ<18>
  VSS(31)  = GND
  DQ(29)  = M_E_DQ<28>
  VSS(30)  = GND
  DQ(25)  = M_E_DQ<24>
  VSS(29)  = GND
  DQS3N  = M_E_DQS_DN<3>
  DQS3P  = M_E_DQS_DP<3>
  VSS(28)  = GND
  DQ(31)  = M_E_DQ<30>
  VSS(27)  = GND
  DQ(27)  = M_E_DQ<26>
  VSS(26)  = GND
  CB(5)  = M_E_ECC<4>
  VSS(25)  = GND
  CB(1)  = M_E_ECC<0>
  VSS(24)  = GND
  DQS8N  = M_E_DQS_DN<8>
  DQS8P  = M_E_DQS_DP<8>
  VSS(23)  = GND
  CB(7)  = M_E_ECC<6>
  VSS(22)  = GND
  CB(3)  = M_E_ECC<2>
  VSS(21)  = GND
  CKE(1)  = M_E_CKE<1>
  VDD(12)  = PVDDQ_DEF
  RFU(0)  = TP_CH_E_DIMM_E0_RFU_0
  VDD(11)  = PVDDQ_DEF
  BG(1)  = M_E_BG<1>
  ALERT_N  = M_E_ALERT_N
  VDD(10)  = PVDDQ_DEF
  A11  = M_E_MA<11>
  A7  = M_E_MA<7>
  VDD(9)  = PVDDQ_DEF
  A5  = M_E_MA<5>
  A4  = M_E_MA<4>
  VDD(8)  = PVDDQ_DEF
  A2  = M_E_MA<2>
  VDD(7)  = PVDDQ_DEF
  CK1P  = M_E_CLK_DP<1>
  CK1N  = M_E_CLK_DN<1>
  VDD(6)  = PVDDQ_DEF
  VTT(0)  = PVTT_DEF
  PAR  = M_E_PAR
  VDD(5)  = PVDDQ_DEF
  BA(1)  = M_E_BA<1>
  A10  = M_E_MA<10>
  VDD(4)  = PVDDQ_DEF
  RFU(1)  = TP_CH_E_DIMM_E0_RFU_1
  A14_WE_N  = M_E_MA<14>
  VDD(3)  = PVDDQ_DEF
  SAVE_N_NC  = FM_ADR_COMPLETE_DEF_N
  VDD(2)  = PVDDQ_DEF
  A13  = M_E_MA<13>
  VDD(1)  = PVDDQ_DEF
  A17  = M_E_MA<17>
  C(2)  = M_E_C<2>
  VDD(0)  = PVDDQ_DEF
  S3_N_C(1)  = M_E_CS_N<3>
  SA(2)  = GND
  VSS(20)  = GND
  DQ(37)  = M_E_DQ<36>
  VSS(19)  = GND
  DQ(33)  = M_E_DQ<32>
  VSS(18)  = GND
  DQS4N  = M_E_DQS_DN<4>
  DQS4P  = M_E_DQS_DP<4>
  VSS(17)  = GND
  DQ(39)  = M_E_DQ<38>
  VSS(16)  = GND
  DQ(35)  = M_E_DQ<34>
  VSS(15)  = GND
  DQ(45)  = M_E_DQ<44>
  VSS(14)  = GND
  DQ(41)  = M_E_DQ<40>
  VSS(13)  = GND
  DQS5N  = M_E_DQS_DN<5>
  DQS5P  = M_E_DQS_DP<5>
  VSS(12)  = GND
  DQ(47)  = M_E_DQ<46>
  VSS(11)  = GND
  DQ(43)  = M_E_DQ<42>
  VSS(10)  = GND
  DQ(53)  = M_E_DQ<52>
  VSS(9)  = GND
  DQ(49)  = M_E_DQ<48>
  VSS(8)  = GND
  DQS6N  = M_E_DQS_DN<6>
  DQS6P  = M_E_DQS_DP<6>
  VSS(7)  = GND
  DQ(55)  = M_E_DQ<54>
  VSS(6)  = GND
  DQ(51)  = M_E_DQ<50>
  VSS(5)  = GND
  DQ(61)  = M_E_DQ<60>
  VSS(4)  = GND
  DQ(57)  = M_E_DQ<56>
  VSS(3)  = GND
  DQS7N  = M_E_DQS_DN<7>
  DQS7P  = M_E_DQS_DP<7>
  VSS(2)  = GND
  DQ(63)  = M_E_DQ<62>
  VSS(1)  = GND
  DQ(59)  = M_E_DQ<58>
  VSS(0)  = GND
  VDDSPD  = PVPP_DEF
  SDA  = SMB_DDR_DEF_VPP_SDA
  VPP(1)  = PVPP_DEF
  VPP(0)  = PVPP_DEF
  VPP(2)  = PVPP_DEF

(kicad_pcb
	(version 20260206)
	(generator "pcbnew")
	(generator_version "10.0")
	(general
		(thickness 1.6)
		(legacy_teardrops no)
	)
	(paper "A4")
	(title_block
		(title "Wiwynn_Tioga_Pass_MB.brd")
		(comment 1 "Tioga Pass / footprint 2096 of 4770 (J4A2), pads 153-202 of 291")
	)
	(layers
		(0 "F.Cu" signal "TOP")
		(4 "In1.Cu" signal "L2GND")
		(6 "In2.Cu" signal "L3")
		(8 "In3.Cu" signal "L4GND")
		(10 "In4.Cu" signal "L5")
		(12 "In5.Cu" signal "L6GND")
		(14 "In6.Cu" signal "L7VCC")
		(16 "In7.Cu" signal "L8VCC")
		(18 "In8.Cu" signal "L9GND")
		(20 "In9.Cu" signal "L10")
		(22 "In10.Cu" signal "L11GND")
		(24 "In11.Cu" signal "L12")
		(26 "In12.Cu" signal "L13GND")
		(2 "B.Cu" signal "BOTTOM")
		(9 "F.Adhes" user "F.Adhesive")
		(11 "B.Adhes" user "B.Adhesive")
		(13 "F.Paste" user "Package Geometry/Pastemask Top")
		(15 "B.Paste" user "Package Geometry/Pastemask Bottom")
		(5 "F.SilkS" user "Ref Des/Silkscreen Top")
		(7 "B.SilkS" user "Ref Des/Silkscreen Bottom")
		(1 "F.Mask" user "Board Geometry/Soldermask Top")
		(3 "B.Mask" user "Board Geometry/Soldermask Bottom")
		(17 "Dwgs.User" user "User.Drawings")
		(19 "Cmts.User" user "User.Comments")
		(21 "Eco1.User" user "User.Eco1")
		(23 "Eco2.User" user "User.Eco2")
		(25 "Edge.Cuts" user "Board Geometry/Outline")
		(27 "Margin" user)
		(31 "F.CrtYd" user "Package Geometry/Place Bound Top")
		(29 "B.CrtYd" user "Package Geometry/Place Bound Bottom")
		(35 "F.Fab" user "Ref Des/Assembly Top")
		(33 "B.Fab" user "Ref Des/Assembly Bottom")
	)
	(footprint ""
		(layer "F.Cu")
		(at 194.700398 -142.6718 90)
		(property "Reference" "J4A2"
			(at -2.369312 42.66311 0)
			(unlocked yes)
			(layer "F.SilkS")
			(effects
				(font
					(size 0.7874 0.5842)
					(thickness 0.1524)
				)
				(justify left)
			)
		)
		(property "Value" ""
			(at 0 0 90)
			(layer "F.Fab")
			(effects
				(font
					(size 1.27 1.27)
				)
			)
		)
		(duplicate_pad_numbers_are_jumpers no)
		(pad "150" smd rect
			(at 4.59994 4.249928 90)
			(size 1.8034 0.508)
			(layers "F.Cu" "F.Mask" "F.Paste")
			(net "M_E_DQ<0>")
		)
		(pad "151" smd rect
			(at 4.59994 5.100066 90)
			(size 1.8034 0.508)
			(layers "F.Cu" "F.Mask" "F.Paste")
			(net "GND")
		)
		(pad "152" smd rect
			(at 4.59994 5.94995 90)
			(size 1.8034 0.508)
			(layers "F.Cu" "F.Mask" "F.Paste")
			(net "M_E_DQS_DN<0>")
		)
		(pad "153" smd rect
			(at 4.59994 6.800088 90)
			(size 1.8034 0.508)
			(layers "F.Cu" "F.Mask" "F.Paste")
			(net "M_E_DQS_DP<0>")
		)
		(pad "154" smd rect
			(at 4.59994 7.649972 90)
			(size 1.8034 0.508)
			(layers "F.Cu" "F.Mask" "F.Paste")
			(net "GND")
		)
		(pad "155" smd rect
			(at 4.59994 8.50011 90)
			(size 1.8034 0.508)
			(layers "F.Cu" "F.Mask" "F.Paste")
			(net "M_E_DQ<6>")
		)
		(pad "156" smd rect
			(at 4.59994 9.349994 90)
			(size 1.8034 0.508)
			(layers "F.Cu" "F.Mask" "F.Paste")
			(net "GND")
		)
		(pad "157" smd rect
			(at 4.59994 10.199878 90)
			(size 1.8034 0.508)
			(layers "F.Cu" "F.Mask" "F.Paste")
			(net "M_E_DQ<2>")
		)
		(pad "158" smd rect
			(at 4.59994 11.050016 90)
			(size 1.8034 0.508)
			(layers "F.Cu" "F.Mask" "F.Paste")
			(net "GND")
		)
		(pad "159" smd rect
			(at 4.59994 11.8999 90)
			(size 1.8034 0.508)
			(layers "F.Cu" "F.Mask" "F.Paste")
			(net "M_E_DQ<12>")
		)
		(pad "160" smd rect
			(at 4.59994 12.750038 90)
			(size 1.8034 0.508)
			(layers "F.Cu" "F.Mask" "F.Paste")
			(net "GND")
		)
		(pad "161" smd rect
			(at 4.59994 13.599922 90)
			(size 1.8034 0.508)
			(layers "F.Cu" "F.Mask" "F.Paste")
			(net "M_E_DQ<8>")
		)
		(pad "162" smd rect
			(at 4.59994 14.45006 90)
			(size 1.8034 0.508)
			(layers "F.Cu" "F.Mask" "F.Paste")
			(net "GND")
		)
		(pad "163" smd rect
			(at 4.59994 15.299944 90)
			(size 1.8034 0.508)
			(layers "F.Cu" "F.Mask" "F.Paste")
			(net "M_E_DQS_DN<1>")
		)
		(pad "164" smd rect
			(at 4.59994 16.150082 90)
			(size 1.8034 0.508)
			(layers "F.Cu" "F.Mask" "F.Paste")
			(net "M_E_DQS_DP<1>")
		)
		(pad "165" smd rect
			(at 4.59994 16.999966 90)
			(size 1.8034 0.508)
			(layers "F.Cu" "F.Mask" "F.Paste")
			(net "GND")
		)
		(pad "166" smd rect
			(at 4.59994 17.850104 90)
			(size 1.8034 0.508)
			(layers "F.Cu" "F.Mask" "F.Paste")
			(net "M_E_DQ<14>")
		)
		(pad "167" smd rect
			(at 4.59994 18.699988 90)
			(size 1.8034 0.508)
			(layers "F.Cu" "F.Mask" "F.Paste")
			(net "GND")
		)
		(pad "168" smd rect
			(at 4.59994 19.550126 90)
			(size 1.8034 0.508)
			(layers "F.Cu" "F.Mask" "F.Paste")
			(net "M_E_DQ<10>")
		)
		(pad "169" smd rect
			(at 4.59994 20.40001 90)
			(size 1.8034 0.508)
			(layers "F.Cu" "F.Mask" "F.Paste")
			(net "GND")
		)
		(pad "170" smd rect
			(at 4.59994 21.249894 90)
			(size 1.8034 0.508)
			(layers "F.Cu" "F.Mask" "F.Paste")
			(net "M_E_DQ<20>")
		)
		(pad "171" smd rect
			(at 4.59994 22.100032 90)
			(size 1.8034 0.508)
			(layers "F.Cu" "F.Mask" "F.Paste")
			(net "GND")
		)
		(pad "172" smd rect
			(at 4.59994 22.949916 90)
			(size 1.8034 0.508)
			(layers "F.Cu" "F.Mask" "F.Paste")
			(net "M_E_DQ<16>")
		)
		(pad "173" smd rect
			(at 4.59994 23.800054 90)
			(size 1.8034 0.508)
			(layers "F.Cu" "F.Mask" "F.Paste")
			(net "GND")
		)
		(pad "174" smd rect
			(at 4.59994 24.649938 90)
			(size 1.8034 0.508)
			(layers "F.Cu" "F.Mask" "F.Paste")
			(net "M_E_DQS_DN<2>")
		)
		(pad "175" smd rect
			(at 4.59994 25.500076 90)
			(size 1.8034 0.508)
			(layers "F.Cu" "F.Mask" "F.Paste")
			(net "M_E_DQS_DP<2>")
		)
		(pad "176" smd rect
			(at 4.59994 26.34996 90)
			(size 1.8034 0.508)
			(layers "F.Cu" "F.Mask" "F.Paste")
			(net "GND")
		)
		(pad "177" smd rect
			(at 4.59994 27.200098 90)
			(size 1.8034 0.508)
			(layers "F.Cu" "F.Mask" "F.Paste")
			(net "M_E_DQ<22>")
		)
		(pad "178" smd rect
			(at 4.59994 28.049982 90)
			(size 1.8034 0.508)
			(layers "F.Cu" "F.Mask" "F.Paste")
			(net "GND")
		)
		(pad "179" smd rect
			(at 4.59994 28.90012 90)
			(size 1.8034 0.508)
			(layers "F.Cu" "F.Mask" "F.Paste")
			(net "M_E_DQ<18>")
		)
		(pad "180" smd rect
			(at 4.59994 29.750004 90)
			(size 1.8034 0.508)
			(layers "F.Cu" "F.Mask" "F.Paste")
			(net "GND")
		)
		(pad "181" smd rect
			(at 4.59994 30.599888 90)
			(size 1.8034 0.508)
			(layers "F.Cu" "F.Mask" "F.Paste")
			(net "M_E_DQ<28>")
		)
		(pad "182" smd rect
			(at 4.59994 31.450026 90)
			(size 1.8034 0.508)
			(layers "F.Cu" "F.Mask" "F.Paste")
			(net "GND")
		)
		(pad "183" smd rect
			(at 4.59994 32.29991 90)
			(size 1.8034 0.508)
			(layers "F.Cu" "F.Mask" "F.Paste")
			(net "M_E_DQ<24>")
		)
		(pad "184" smd rect
			(at 4.59994 33.150048 90)
			(size 1.8034 0.508)
			(layers "F.Cu" "F.Mask" "F.Paste")
			(net "GND")
		)
		(pad "185" smd rect
			(at 4.59994 33.999932 90)
			(size 1.8034 0.508)
			(layers "F.Cu" "F.Mask" "F.Paste")
			(net "M_E_DQS_DN<3>")
		)
		(pad "186" smd rect
			(at 4.59994 34.85007 90)
			(size 1.8034 0.508)
			(layers "F.Cu" "F.Mask" "F.Paste")
			(net "M_E_DQS_DP<3>")
		)
		(pad "187" smd rect
			(at 4.59994 35.699954 90)
			(size 1.8034 0.508)
			(layers "F.Cu" "F.Mask" "F.Paste")
			(net "GND")
		)
		(pad "188" smd rect
			(at 4.59994 36.550092 90)
			(size 1.8034 0.508)
			(layers "F.Cu" "F.Mask" "F.Paste")
			(net "M_E_DQ<30>")
		)
		(pad "189" smd rect
			(at 4.59994 37.399976 90)
			(size 1.8034 0.508)
			(layers "F.Cu" "F.Mask" "F.Paste")
			(net "GND")
		)
		(pad "190" smd rect
			(at 4.59994 38.250114 90)
			(size 1.8034 0.508)
			(layers "F.Cu" "F.Mask" "F.Paste")
			(net "M_E_DQ<26>")
		)
		(pad "191" smd rect
			(at 4.59994 39.099998 90)
			(size 1.8034 0.508)
			(layers "F.Cu" "F.Mask" "F.Paste")
			(net "GND")
		)
		(pad "192" smd rect
			(at 4.59994 39.949882 90)
			(size 1.8034 0.508)
			(layers "F.Cu" "F.Mask" "F.Paste")
			(net "M_E_ECC<4>")
		)
		(pad "193" smd rect
			(at 4.59994 40.80002 90)
			(size 1.8034 0.508)
			(layers "F.Cu" "F.Mask" "F.Paste")
			(net "GND")
		)
		(pad "194" smd rect
			(at 4.59994 41.649904 90)
			(size 1.8034 0.508)
			(layers "F.Cu" "F.Mask" "F.Paste")
			(net "M_E_ECC<0>")
		)
		(pad "195" smd rect
			(at 4.59994 42.500042 90)
			(size 1.8034 0.508)
			(layers "F.Cu" "F.Mask" "F.Paste")
			(net "GND")
		)
		(pad "196" smd rect
			(at 4.59994 43.349926 90)
			(size 1.8034 0.508)
			(layers "F.Cu" "F.Mask" "F.Paste")
			(net "M_E_DQS_DN<8>")
		)
		(pad "197" smd rect
			(at 4.59994 44.200064 90)
			(size 1.8034 0.508)
			(layers "F.Cu" "F.Mask" "F.Paste")
			(net "M_E_DQS_DP<8>")
		)
		(pad "198" smd rect
			(at 4.59994 45.049948 90)
			(size 1.8034 0.508)
			(layers "F.Cu" "F.Mask" "F.Paste")
			(net "GND")
		)
		(pad "199" smd rect
			(at 4.59994 45.900086 90)
			(size 1.8034 0.508)
			(layers "F.Cu" "F.Mask" "F.Paste")
			(net "M_E_ECC<6>")
		)
	)
)
